(kicad_pcb
	(version 20260206)
	(generator "pcbnew")
	(generator_version "10.0")
	(general
		(thickness 1.6)
		(legacy_teardrops no)
	)
	(paper "A4")
	(title_block
		(title "04192023_DAF0TMB3IC0_F0TG_MB_C_brd_V02_OCP.brd")
		(comment 1 "Grand Teton / footprints 342-347 of 8354")
	)
	(layers
		(0 "F.Cu" signal "TOP")
		(4 "In1.Cu" signal "GND")
		(6 "In2.Cu" signal "IN1")
		(8 "In3.Cu" signal "GND1")
		(10 "In4.Cu" signal "IN2")
		(12 "In5.Cu" signal "GND2")
		(14 "In6.Cu" signal "IN3")
		(16 "In7.Cu" signal "GND3")
		(18 "In8.Cu" signal "VCC")
		(20 "In9.Cu" signal "VCC1")
		(22 "In10.Cu" signal "GND4")
		(24 "In11.Cu" signal "IN4")
		(26 "In12.Cu" signal "GND5")
		(28 "In13.Cu" signal "IN5")
		(30 "In14.Cu" signal "GND6")
		(32 "In15.Cu" signal "IN6")
		(34 "In16.Cu" signal "GND7")
		(2 "B.Cu" signal "BOTTOM")
		(9 "F.Adhes" user "F.Adhesive")
		(11 "B.Adhes" user "B.Adhesive")
		(13 "F.Paste" user "Package Geometry/Pastemask Top")
		(15 "B.Paste" user "Package Geometry/Pastemask Bottom")
		(5 "F.SilkS" user "Ref Des/Silkscreen Top")
		(7 "B.SilkS" user "Ref Des/Silkscreen Bottom")
		(1 "F.Mask" user "Board Geometry/Soldermask Top")
		(3 "B.Mask" user "Board Geometry/Soldermask Bottom")
		(17 "Dwgs.User" user "User.Drawings")
		(19 "Cmts.User" user "User.Comments")
		(21 "Eco1.User" user "User.Eco1")
		(23 "Eco2.User" user "User.Eco2")
		(25 "Edge.Cuts" user "Board Geometry/Outline")
		(27 "Margin" user)
		(31 "F.CrtYd" user "Package Geometry/Place Bound Top")
		(29 "B.CrtYd" user "Package Geometry/Place Bound Bottom")
		(35 "F.Fab" user "Ref Des/Assembly Top")
		(33 "B.Fab" user "Ref Des/Assembly Bottom")
	)
	(footprint ""
		(layer "F.Cu")
		(at 179.225956 -348.29115 180)
		(property "Reference" "PC315"
			(at 0 0 180)
			(layer "F.SilkS")
			(hide yes)
			(effects
				(font
					(size 1.27 1.27)
				)
			)
		)
		(property "Value" ""
			(at 0 0 180)
			(layer "F.Fab")
			(effects
				(font
					(size 1.27 1.27)
				)
			)
		)
		(duplicate_pad_numbers_are_jumpers no)
		(fp_line
			(start 0.7874 0.4064)
			(end -0.7874 0.4064)
			(stroke
				(width 0.1524)
				(type default)
			)
			(layer "F.SilkS")
		)
		(fp_line
			(start 0.7874 -0.4064)
			(end 0.7874 0.4064)
			(stroke
				(width 0.1524)
				(type default)
			)
			(layer "F.SilkS")
		)
		(fp_line
			(start -0.7874 0.4064)
			(end -0.7874 -0.4064)
			(stroke
				(width 0.1524)
				(type default)
			)
			(layer "F.SilkS")
		)
		(fp_line
			(start -0.7874 -0.4064)
			(end 0.7874 -0.4064)
			(stroke
				(width 0.1524)
				(type default)
			)
			(layer "F.SilkS")
		)
		(fp_line
			(start 0.67945 0.3048)
			(end 0.120396 0.3048)
			(stroke
				(width 0.1)
				(type default)
			)
			(layer "F.Fab")
		)
		(fp_line
			(start 0.67945 -0.3048)
			(end 0.67945 0.3048)
			(stroke
				(width 0.1)
				(type default)
			)
			(layer "F.Fab")
		)
		(fp_line
			(start 0.12065 -0.2794)
			(end 0.12065 -0.3048)
			(stroke
				(width 0.1)
				(type default)
			)
			(layer "F.Fab")
		)
		(fp_line
			(start 0.12065 -0.3048)
			(end 0.67945 -0.3048)
			(stroke
				(width 0.1)
				(type default)
			)
			(layer "F.Fab")
		)
		(fp_line
			(start 0.120396 0.3048)
			(end 0.120396 0.2794)
			(stroke
				(width 0.1)
				(type default)
			)
			(layer "F.Fab")
		)
		(fp_line
			(start 0.120396 0.2794)
			(end -0.12065 0.2794)
			(stroke
				(width 0.1)
				(type default)
			)
			(layer "F.Fab")
		)
		(fp_line
			(start -0.12065 0.3048)
			(end -0.67945 0.3048)
			(stroke
				(width 0.1)
				(type default)
			)
			(layer "F.Fab")
		)
		(fp_line
			(start -0.12065 0.2794)
			(end -0.12065 0.3048)
			(stroke
				(width 0.1)
				(type default)
			)
			(layer "F.Fab")
		)
		(fp_line
			(start -0.12065 -0.2794)
			(end 0.12065 -0.2794)
			(stroke
				(width 0.1)
				(type default)
			)
			(layer "F.Fab")
		)
		(fp_line
			(start -0.12065 -0.305054)
			(end -0.12065 -0.2794)
			(stroke
				(width 0.1)
				(type default)
			)
			(layer "F.Fab")
		)
		(fp_line
			(start -0.67945 0.3048)
			(end -0.67945 -0.305054)
			(stroke
				(width 0.1)
				(type default)
			)
			(layer "F.Fab")
		)
		(fp_line
			(start -0.67945 -0.305054)
			(end -0.12065 -0.305054)
			(stroke
				(width 0.1)
				(type default)
			)
			(layer "F.Fab")
		)
		(pad "1" smd circle
			(at -0.40005 0 180)
			(size 0 0)
			(layers "F.Cu" "F.Mask" "F.Paste")
			(net "SW_PVDD11_S3_P1_SW1")
		)
		(pad "2" smd circle
			(at 0.40005 0 180)
			(size 0 0)
			(layers "F.Cu" "F.Mask" "F.Paste")
			(net "SW_PVDD11_S3_P1_SW1_RC")
		)
	)
	(footprint ""
		(layer "F.Cu")
		(at 284.556962 -426.19549 90)
		(property "Reference" "C76"
			(at 0 0 90)
			(layer "F.SilkS")
			(hide yes)
			(effects
				(font
					(size 1.27 1.27)
				)
			)
		)
		(property "Value" ""
			(at 0 0 90)
			(layer "F.Fab")
			(effects
				(font
					(size 1.27 1.27)
				)
			)
		)
		(duplicate_pad_numbers_are_jumpers no)
		(fp_line
			(start 0.7874 -0.4064)
			(end 0.7874 0.4064)
			(stroke
				(width 0.1524)
				(type default)
			)
			(layer "F.SilkS")
		)
		(fp_line
			(start -0.7874 -0.4064)
			(end 0.7874 -0.4064)
			(stroke
				(width 0.1524)
				(type default)
			)
			(layer "F.SilkS")
		)
		(fp_line
			(start 0.7874 0.4064)
			(end -0.7874 0.4064)
			(stroke
				(width 0.1524)
				(type default)
			)
			(layer "F.SilkS")
		)
		(fp_line
			(start -0.7874 0.4064)
			(end -0.7874 -0.4064)
			(stroke
				(width 0.1524)
				(type default)
			)
			(layer "F.SilkS")
		)
		(fp_line
			(start -0.12065 -0.305054)
			(end -0.12065 -0.2794)
			(stroke
				(width 0.1)
				(type default)
			)
			(layer "F.Fab")
		)
		(fp_line
			(start -0.67945 -0.305054)
			(end -0.12065 -0.305054)
			(stroke
				(width 0.1)
				(type default)
			)
			(layer "F.Fab")
		)
		(fp_line
			(start 0.67945 -0.3048)
			(end 0.67945 0.3048)
			(stroke
				(width 0.1)
				(type default)
			)
			(layer "F.Fab")
		)
		(fp_line
			(start 0.12065 -0.3048)
			(end 0.67945 -0.3048)
			(stroke
				(width 0.1)
				(type default)
			)
			(layer "F.Fab")
		)
		(fp_line
			(start 0.12065 -0.2794)
			(end 0.12065 -0.3048)
			(stroke
				(width 0.1)
				(type default)
			)
			(layer "F.Fab")
		)
		(fp_line
			(start -0.12065 -0.2794)
			(end 0.12065 -0.2794)
			(stroke
				(width 0.1)
				(type default)
			)
			(layer "F.Fab")
		)
		(fp_line
			(start 0.120396 0.2794)
			(end -0.12065 0.2794)
			(stroke
				(width 0.1)
				(type default)
			)
			(layer "F.Fab")
		)
		(fp_line
			(start -0.12065 0.2794)
			(end -0.12065 0.3048)
			(stroke
				(width 0.1)
				(type default)
			)
			(layer "F.Fab")
		)
		(fp_line
			(start 0.67945 0.3048)
			(end 0.120396 0.3048)
			(stroke
				(width 0.1)
				(type default)
			)
			(layer "F.Fab")
		)
		(fp_line
			(start 0.120396 0.3048)
			(end 0.120396 0.2794)
			(stroke
				(width 0.1)
				(type default)
			)
			(layer "F.Fab")
		)
		(fp_line
			(start -0.12065 0.3048)
			(end -0.67945 0.3048)
			(stroke
				(width 0.1)
				(type default)
			)
			(layer "F.Fab")
		)
		(fp_line
			(start -0.67945 0.3048)
			(end -0.67945 -0.305054)
			(stroke
				(width 0.1)
				(type default)
			)
			(layer "F.Fab")
		)
		(pad "1" smd circle
			(at -0.40005 0 90)
			(size 0 0)
			(layers "F.Cu" "F.Mask" "F.Paste")
			(net "P3V3_9ZXL045_P0_VDDA")
		)
		(pad "2" smd circle
			(at 0.40005 0 90)
			(size 0 0)
			(layers "F.Cu" "F.Mask" "F.Paste")
			(net "GND")
		)
	)
	(footprint ""
		(layer "F.Cu")
		(at 210.485482 -102.958138)
		(property "Reference" "R1340"
			(at 0 0 0)
			(layer "F.SilkS")
			(hide yes)
			(effects
				(font
					(size 1.27 1.27)
				)
			)
		)
		(property "Value" ""
			(at 0 0 0)
			(layer "F.Fab")
			(effects
				(font
					(size 1.27 1.27)
				)
			)
		)
		(duplicate_pad_numbers_are_jumpers no)
		(fp_line
			(start -0.7874 -0.4064)
			(end 0.7874 -0.4064)
			(stroke
				(width 0.1524)
				(type default)
			)
			(layer "F.SilkS")
		)
		(fp_line
			(start -0.7874 0.4064)
			(end -0.7874 -0.4064)
			(stroke
				(width 0.1524)
				(type default)
			)
			(layer "F.SilkS")
		)
		(fp_line
			(start 0.7874 -0.4064)
			(end 0.7874 0.4064)
			(stroke
				(width 0.1524)
				(type default)
			)
			(layer "F.SilkS")
		)
		(fp_line
			(start 0.7874 0.4064)
			(end -0.7874 0.4064)
			(stroke
				(width 0.1524)
				(type default)
			)
			(layer "F.SilkS")
		)
		(fp_line
			(start -0.67945 -0.305054)
			(end -0.12065 -0.305054)
			(stroke
				(width 0.1)
				(type default)
			)
			(layer "F.Fab")
		)
		(fp_line
			(start -0.67945 0.3048)
			(end -0.67945 -0.305054)
			(stroke
				(width 0.1)
				(type default)
			)
			(layer "F.Fab")
		)
		(fp_line
			(start -0.12065 -0.305054)
			(end -0.12065 -0.2794)
			(stroke
				(width 0.1)
				(type default)
			)
			(layer "F.Fab")
		)
		(fp_line
			(start -0.12065 -0.2794)
			(end 0.12065 -0.2794)
			(stroke
				(width 0.1)
				(type default)
			)
			(layer "F.Fab")
		)
		(fp_line
			(start -0.12065 0.2794)
			(end -0.12065 0.3048)
			(stroke
				(width 0.1)
				(type default)
			)
			(layer "F.Fab")
		)
		(fp_line
			(start -0.12065 0.3048)
			(end -0.67945 0.3048)
			(stroke
				(width 0.1)
				(type default)
			)
			(layer "F.Fab")
		)
		(fp_line
			(start 0.120396 0.2794)
			(end -0.12065 0.2794)
			(stroke
				(width 0.1)
				(type default)
			)
			(layer "F.Fab")
		)
		(fp_line
			(start 0.120396 0.3048)
			(end 0.120396 0.2794)
			(stroke
				(width 0.1)
				(type default)
			)
			(layer "F.Fab")
		)
		(fp_line
			(start 0.12065 -0.3048)
			(end 0.67945 -0.3048)
			(stroke
				(width 0.1)
				(type default)
			)
			(layer "F.Fab")
		)
		(fp_line
			(start 0.12065 -0.2794)
			(end 0.12065 -0.3048)
			(stroke
				(width 0.1)
				(type default)
			)
			(layer "F.Fab")
		)
		(fp_line
			(start 0.67945 -0.3048)
			(end 0.67945 0.3048)
			(stroke
				(width 0.1)
				(type default)
			)
			(layer "F.Fab")
		)
		(fp_line
			(start 0.67945 0.3048)
			(end 0.120396 0.3048)
			(stroke
				(width 0.1)
				(type default)
			)
			(layer "F.Fab")
		)
		(pad "1" smd circle
			(at -0.40005 0)
			(size 0 0)
			(layers "F.Cu" "F.Mask" "F.Paste")
			(net "OCP_SFF_P3V3_P12V_ADC_ALERT")
		)
		(pad "2" smd circle
			(at 0.40005 0)
			(size 0 0)
			(layers "F.Cu" "F.Mask" "F.Paste")
			(net "OCP_SFF_P3V3_P12V_ADC_R_ALERT")
		)
	)
	(footprint ""
		(layer "F.Cu")
		(at 197.269608 -110.577376 180)
		(property "Reference" "R176"
			(at 0 0 180)
			(layer "F.SilkS")
			(hide yes)
			(effects
				(font
					(size 1.27 1.27)
				)
			)
		)
		(property "Value" ""
			(at 0 0 180)
			(layer "F.Fab")
			(effects
				(font
					(size 1.27 1.27)
				)
			)
		)
		(duplicate_pad_numbers_are_jumpers no)
		(fp_line
			(start 0.7874 0.4064)
			(end -0.7874 0.4064)
			(stroke
				(width 0.1524)
				(type default)
			)
			(layer "F.SilkS")
		)
		(fp_line
			(start 0.7874 -0.4064)
			(end 0.7874 0.4064)
			(stroke
				(width 0.1524)
				(type default)
			)
			(layer "F.SilkS")
		)
		(fp_line
			(start -0.7874 0.4064)
			(end -0.7874 -0.4064)
			(stroke
				(width 0.1524)
				(type default)
			)
			(layer "F.SilkS")
		)
		(fp_line
			(start -0.7874 -0.4064)
			(end 0.7874 -0.4064)
			(stroke
				(width 0.1524)
				(type default)
			)
			(layer "F.SilkS")
		)
		(fp_line
			(start 0.67945 0.3048)
			(end 0.120396 0.3048)
			(stroke
				(width 0.1)
				(type default)
			)
			(layer "F.Fab")
		)
		(fp_line
			(start 0.67945 -0.3048)
			(end 0.67945 0.3048)
			(stroke
				(width 0.1)
				(type default)
			)
			(layer "F.Fab")
		)
		(fp_line
			(start 0.12065 -0.2794)
			(end 0.12065 -0.3048)
			(stroke
				(width 0.1)
				(type default)
			)
			(layer "F.Fab")
		)
		(fp_line
			(start 0.12065 -0.3048)
			(end 0.67945 -0.3048)
			(stroke
				(width 0.1)
				(type default)
			)
			(layer "F.Fab")
		)
		(fp_line
			(start 0.120396 0.3048)
			(end 0.120396 0.2794)
			(stroke
				(width 0.1)
				(type default)
			)
			(layer "F.Fab")
		)
		(fp_line
			(start 0.120396 0.2794)
			(end -0.12065 0.2794)
			(stroke
				(width 0.1)
				(type default)
			)
			(layer "F.Fab")
		)
		(fp_line
			(start -0.12065 0.3048)
			(end -0.67945 0.3048)
			(stroke
				(width 0.1)
				(type default)
			)
			(layer "F.Fab")
		)
		(fp_line
			(start -0.12065 0.2794)
			(end -0.12065 0.3048)
			(stroke
				(width 0.1)
				(type default)
			)
			(layer "F.Fab")
		)
		(fp_line
			(start -0.12065 -0.2794)
			(end 0.12065 -0.2794)
			(stroke
				(width 0.1)
				(type default)
			)
			(layer "F.Fab")
		)
		(fp_line
			(start -0.12065 -0.305054)
			(end -0.12065 -0.2794)
			(stroke
				(width 0.1)
				(type default)
			)
			(layer "F.Fab")
		)
		(fp_line
			(start -0.67945 0.3048)
			(end -0.67945 -0.305054)
			(stroke
				(width 0.1)
				(type default)
			)
			(layer "F.Fab")
		)
		(fp_line
			(start -0.67945 -0.305054)
			(end -0.12065 -0.305054)
			(stroke
				(width 0.1)
				(type default)
			)
			(layer "F.Fab")
		)
		(pad "1" smd circle
			(at -0.40005 0 180)
			(size 0 0)
			(layers "F.Cu" "F.Mask" "F.Paste")
			(net "PVDD18_S5_P0_EN")
		)
		(pad "2" smd circle
			(at 0.40005 0 180)
			(size 0 0)
			(layers "F.Cu" "F.Mask" "F.Paste")
			(net "FM_PVDD18_S5_P0_EN")
		)
	)
	(footprint ""
		(layer "F.Cu")
		(at 208.054956 -30.276292 90)
		(property "Reference" "R3612"
			(at 0 0 90)
			(layer "F.SilkS")
			(hide yes)
			(effects
				(font
					(size 1.27 1.27)
				)
			)
		)
		(property "Value" ""
			(at 0 0 90)
			(layer "F.Fab")
			(effects
				(font
					(size 1.27 1.27)
				)
			)
		)
		(duplicate_pad_numbers_are_jumpers no)
		(fp_line
			(start 0.7874 -0.4064)
			(end 0.7874 0.4064)
			(stroke
				(width 0.1524)
				(type default)
			)
			(layer "F.SilkS")
		)
		(fp_line
			(start -0.7874 -0.4064)
			(end 0.7874 -0.4064)
			(stroke
				(width 0.1524)
				(type default)
			)
			(layer "F.SilkS")
		)
		(fp_line
			(start 0.7874 0.4064)
			(end -0.7874 0.4064)
			(stroke
				(width 0.1524)
				(type default)
			)
			(layer "F.SilkS")
		)
		(fp_line
			(start -0.7874 0.4064)
			(end -0.7874 -0.4064)
			(stroke
				(width 0.1524)
				(type default)
			)
			(layer "F.SilkS")
		)
		(fp_line
			(start -0.12065 -0.305054)
			(end -0.12065 -0.2794)
			(stroke
				(width 0.1)
				(type default)
			)
			(layer "F.Fab")
		)
		(fp_line
			(start -0.67945 -0.305054)
			(end -0.12065 -0.305054)
			(stroke
				(width 0.1)
				(type default)
			)
			(layer "F.Fab")
		)
		(fp_line
			(start 0.67945 -0.3048)
			(end 0.67945 0.3048)
			(stroke
				(width 0.1)
				(type default)
			)
			(layer "F.Fab")
		)
		(fp_line
			(start 0.12065 -0.3048)
			(end 0.67945 -0.3048)
			(stroke
				(width 0.1)
				(type default)
			)
			(layer "F.Fab")
		)
		(fp_line
			(start 0.12065 -0.2794)
			(end 0.12065 -0.3048)
			(stroke
				(width 0.1)
				(type default)
			)
			(layer "F.Fab")
		)
		(fp_line
			(start -0.12065 -0.2794)
			(end 0.12065 -0.2794)
			(stroke
				(width 0.1)
				(type default)
			)
			(layer "F.Fab")
		)
		(fp_line
			(start 0.120396 0.2794)
			(end -0.12065 0.2794)
			(stroke
				(width 0.1)
				(type default)
			)
			(layer "F.Fab")
		)
		(fp_line
			(start -0.12065 0.2794)
			(end -0.12065 0.3048)
			(stroke
				(width 0.1)
				(type default)
			)
			(layer "F.Fab")
		)
		(fp_line
			(start 0.67945 0.3048)
			(end 0.120396 0.3048)
			(stroke
				(width 0.1)
				(type default)
			)
			(layer "F.Fab")
		)
		(fp_line
			(start 0.120396 0.3048)
			(end 0.120396 0.2794)
			(stroke
				(width 0.1)
				(type default)
			)
			(layer "F.Fab")
		)
		(fp_line
			(start -0.12065 0.3048)
			(end -0.67945 0.3048)
			(stroke
				(width 0.1)
				(type default)
			)
			(layer "F.Fab")
		)
		(fp_line
			(start -0.67945 0.3048)
			(end -0.67945 -0.305054)
			(stroke
				(width 0.1)
				(type default)
			)
			(layer "F.Fab")
		)
		(pad "1" smd circle
			(at -0.40005 0 90)
			(size 0 0)
			(layers "F.Cu" "F.Mask" "F.Paste")
			(net "GND")
		)
		(pad "2" smd circle
			(at 0.40005 0 90)
			(size 0 0)
			(layers "F.Cu" "F.Mask" "F.Paste")
			(net "INA230_5_A1")
		)
	)
	(footprint ""
		(layer "F.Cu")
		(at 447.687192 -22.125178 180)
		(property "Reference" "PR3781"
			(at 0 0 180)
			(layer "F.SilkS")
			(hide yes)
			(effects
				(font
					(size 1.27 1.27)
				)
			)
		)
		(property "Value" ""
			(at 0 0 180)
			(layer "F.Fab")
			(effects
				(font
					(size 1.27 1.27)
				)
			)
		)
		(duplicate_pad_numbers_are_jumpers no)
		(fp_line
			(start 0.7874 0.4064)
			(end -0.7874 0.4064)
			(stroke
				(width 0.1524)
				(type default)
			)
			(layer "F.SilkS")
		)
		(fp_line
			(start 0.7874 -0.4064)
			(end 0.7874 0.4064)
			(stroke
				(width 0.1524)
				(type default)
			)
			(layer "F.SilkS")
		)
		(fp_line
			(start -0.7874 0.4064)
			(end -0.7874 -0.4064)
			(stroke
				(width 0.1524)
				(type default)
			)
			(layer "F.SilkS")
		)
		(fp_line
			(start -0.7874 -0.4064)
			(end 0.7874 -0.4064)
			(stroke
				(width 0.1524)
				(type default)
			)
			(layer "F.SilkS")
		)
		(fp_line
			(start 0.67945 0.3048)
			(end 0.120396 0.3048)
			(stroke
				(width 0.1)
				(type default)
			)
			(layer "F.Fab")
		)
		(fp_line
			(start 0.67945 -0.3048)
			(end 0.67945 0.3048)
			(stroke
				(width 0.1)
				(type default)
			)
			(layer "F.Fab")
		)
		(fp_line
			(start 0.12065 -0.2794)
			(end 0.12065 -0.3048)
			(stroke
				(width 0.1)
				(type default)
			)
			(layer "F.Fab")
		)
		(fp_line
			(start 0.12065 -0.3048)
			(end 0.67945 -0.3048)
			(stroke
				(width 0.1)
				(type default)
			)
			(layer "F.Fab")
		)
		(fp_line
			(start 0.120396 0.3048)
			(end 0.120396 0.2794)
			(stroke
				(width 0.1)
				(type default)
			)
			(layer "F.Fab")
		)
		(fp_line
			(start 0.120396 0.2794)
			(end -0.12065 0.2794)
			(stroke
				(width 0.1)
				(type default)
			)
			(layer "F.Fab")
		)
		(fp_line
			(start -0.12065 0.3048)
			(end -0.67945 0.3048)
			(stroke
				(width 0.1)
				(type default)
			)
			(layer "F.Fab")
		)
		(fp_line
			(start -0.12065 0.2794)
			(end -0.12065 0.3048)
			(stroke
				(width 0.1)
				(type default)
			)
			(layer "F.Fab")
		)
		(fp_line
			(start -0.12065 -0.2794)
			(end 0.12065 -0.2794)
			(stroke
				(width 0.1)
				(type default)
			)
			(layer "F.Fab")
		)
		(fp_line
			(start -0.12065 -0.305054)
			(end -0.12065 -0.2794)
			(stroke
				(width 0.1)
				(type default)
			)
			(layer "F.Fab")
		)
		(fp_line
			(start -0.67945 0.3048)
			(end -0.67945 -0.305054)
			(stroke
				(width 0.1)
				(type default)
			)
			(layer "F.Fab")
		)
		(fp_line
			(start -0.67945 -0.305054)
			(end -0.12065 -0.305054)
			(stroke
				(width 0.1)
				(type default)
			)
			(layer "F.Fab")
		)
		(pad "1" smd circle
			(at -0.40005 0 180)
			(size 0 0)
			(layers "F.Cu" "F.Mask" "F.Paste")
			(net "P12V_OCP_SENSE_1")
		)
		(pad "2" smd circle
			(at 0.40005 0 180)
			(size 0 0)
			(layers "F.Cu" "F.Mask" "F.Paste")
			(net "GND")
		)
	)
)
